(kicad_pcb
	(version 20260206)
	(generator "pcbnew")
	(generator_version "10.0")
	(general
		(thickness 1.6)
		(legacy_teardrops no)
	)
	(paper "A4")
	(title_block
		(title "04192023_DAF0TMB3IC0_F0TG_MB_C_brd_V02_OCP.brd")
		(comment 1 "Grand Teton / footprint 2783 of 8354 (U26), pads 5451-5559 of 6102")
	)
	(layers
		(0 "F.Cu" signal "TOP")
		(4 "In1.Cu" signal "GND")
		(6 "In2.Cu" signal "IN1")
		(8 "In3.Cu" signal "GND1")
		(10 "In4.Cu" signal "IN2")
		(12 "In5.Cu" signal "GND2")
		(14 "In6.Cu" signal "IN3")
		(16 "In7.Cu" signal "GND3")
		(18 "In8.Cu" signal "VCC")
		(20 "In9.Cu" signal "VCC1")
		(22 "In10.Cu" signal "GND4")
		(24 "In11.Cu" signal "IN4")
		(26 "In12.Cu" signal "GND5")
		(28 "In13.Cu" signal "IN5")
		(30 "In14.Cu" signal "GND6")
		(32 "In15.Cu" signal "IN6")
		(34 "In16.Cu" signal "GND7")
		(2 "B.Cu" signal "BOTTOM")
		(9 "F.Adhes" user "F.Adhesive")
		(11 "B.Adhes" user "B.Adhesive")
		(13 "F.Paste" user "Package Geometry/Pastemask Top")
		(15 "B.Paste" user "Package Geometry/Pastemask Bottom")
		(5 "F.SilkS" user "Ref Des/Silkscreen Top")
		(7 "B.SilkS" user "Ref Des/Silkscreen Bottom")
		(1 "F.Mask" user "Board Geometry/Soldermask Top")
		(3 "B.Mask" user "Board Geometry/Soldermask Bottom")
		(17 "Dwgs.User" user "User.Drawings")
		(19 "Cmts.User" user "User.Comments")
		(21 "Eco1.User" user "User.Eco1")
		(23 "Eco2.User" user "User.Eco2")
		(25 "Edge.Cuts" user "Board Geometry/Outline")
		(27 "Margin" user)
		(31 "F.CrtYd" user "Package Geometry/Place Bound Top")
		(29 "B.CrtYd" user "Package Geometry/Place Bound Bottom")
		(35 "F.Fab" user "Ref Des/Assembly Top")
		(33 "B.Fab" user "Ref Des/Assembly Bottom")
	)
	(footprint ""
		(layer "F.Cu")
		(at 111.927894 -258.880356 180)
		(property "Reference" "U26"
			(at -45.05579 -61.794136 0)
			(unlocked yes)
			(layer "F.SilkS")
			(effects
				(font
					(size 0.7874 0.5842)
					(thickness 0.1524)
				)
			)
		)
		(property "Value" ""
			(at 0 0 180)
			(layer "F.Fab")
			(effects
				(font
					(size 1.27 1.27)
				)
			)
		)
		(duplicate_pad_numbers_are_jumpers no)
		(pad "L72" smd circle
			(at 31.640018 -28.710128 180)
			(size 0.450088 0.450088)
			(layers "F.Cu" "F.Mask" "F.Paste")
			(net "PVDDIO_P1")
		)
		(pad "L73" smd circle
			(at 32.580072 -28.710128 180)
			(size 0.450088 0.450088)
			(layers "F.Cu" "F.Mask" "F.Paste")
			(net "M_A_CPU1_SA_DQ<7>")
		)
		(pad "L74" smd circle
			(at 33.519872 -28.710128 180)
			(size 0.450088 0.450088)
			(layers "F.Cu" "F.Mask" "F.Paste")
			(net "M_A_CPU1_SA_DQ<8>")
		)
		(pad "L75" smd circle
			(at 34.459926 -28.710128 180)
			(size 0.450088 0.450088)
			(layers "F.Cu" "F.Mask" "F.Paste")
			(net "GND")
		)
		(pad "M2" smd circle
			(at -33.690052 -27.900122 180)
			(size 0.450088 0.450088)
			(layers "F.Cu" "F.Mask" "F.Paste")
			(net "M_G_CPU1_SA_DQ<10>")
		)
		(pad "M3" smd circle
			(at -32.749998 -27.900122 180)
			(size 0.450088 0.450088)
			(layers "F.Cu" "F.Mask" "F.Paste")
			(net "GND")
		)
		(pad "M4" smd circle
			(at -31.809944 -27.900122 180)
			(size 0.450088 0.450088)
			(layers "F.Cu" "F.Mask" "F.Paste")
			(net "M_G_CPU1_SA_DQ<9>")
		)
		(pad "M5" smd circle
			(at -30.86989 -27.900122 180)
			(size 0.450088 0.450088)
			(layers "F.Cu" "F.Mask" "F.Paste")
			(net "GND")
		)
		(pad "M6" smd circle
			(at -29.93009 -27.900122 180)
			(size 0.450088 0.450088)
			(layers "F.Cu" "F.Mask" "F.Paste")
			(net "M_K_CPU1_SA_DQ<10>")
		)
		(pad "M7" smd circle
			(at -28.990036 -27.900122 180)
			(size 0.450088 0.450088)
			(layers "F.Cu" "F.Mask" "F.Paste")
			(net "M_K_CPU1_SA_DQ<9>")
		)
		(pad "M8" smd circle
			(at -28.049982 -27.900122 180)
			(size 0.450088 0.450088)
			(layers "F.Cu" "F.Mask" "F.Paste")
			(net "GND")
		)
		(pad "M9" smd circle
			(at -27.109928 -27.900122 180)
			(size 0.450088 0.450088)
			(layers "F.Cu" "F.Mask" "F.Paste")
			(net "M_L_CPU1_SA_DQ<10>")
		)
		(pad "M10" smd circle
			(at -26.170128 -27.900122 180)
			(size 0.450088 0.450088)
			(layers "F.Cu" "F.Mask" "F.Paste")
			(net "GND")
		)
		(pad "M11" smd circle
			(at -25.230074 -27.900122 180)
			(size 0.450088 0.450088)
			(layers "F.Cu" "F.Mask" "F.Paste")
			(net "M_L_CPU1_SA_DQ<9>")
		)
		(pad "M12" smd circle
			(at -24.29002 -27.900122 180)
			(size 0.450088 0.450088)
			(layers "F.Cu" "F.Mask" "F.Paste")
			(net "GND")
		)
		(pad "M13" smd circle
			(at -23.349966 -27.900122 180)
			(size 0.450088 0.450088)
			(layers "F.Cu" "F.Mask" "F.Paste")
			(net "M_H_CPU1_SA_DQ<10>")
		)
		(pad "M14" smd circle
			(at -22.409912 -27.900122 180)
			(size 0.450088 0.450088)
			(layers "F.Cu" "F.Mask" "F.Paste")
			(net "M_H_CPU1_SA_DQ<9>")
		)
		(pad "M15" smd circle
			(at -21.470112 -27.900122 180)
			(size 0.450088 0.450088)
			(layers "F.Cu" "F.Mask" "F.Paste")
			(net "GND")
		)
		(pad "M16" smd circle
			(at -20.530058 -27.900122 180)
			(size 0.450088 0.450088)
			(layers "F.Cu" "F.Mask" "F.Paste")
			(net "M_J_CPU1_SA_DQ<10>")
		)
		(pad "M17" smd circle
			(at -19.590004 -27.900122 180)
			(size 0.450088 0.450088)
			(layers "F.Cu" "F.Mask" "F.Paste")
			(net "GND")
		)
		(pad "M18" smd circle
			(at -18.64995 -27.900122 180)
			(size 0.450088 0.450088)
			(layers "F.Cu" "F.Mask" "F.Paste")
			(net "M_J_CPU1_SA_DQ<9>")
		)
		(pad "M19" smd circle
			(at -17.709896 -27.900122 180)
			(size 0.450088 0.450088)
			(layers "F.Cu" "F.Mask" "F.Paste")
			(net "GND")
		)
		(pad "M20" smd circle
			(at -16.770096 -27.900122 180)
			(size 0.450088 0.450088)
			(layers "F.Cu" "F.Mask" "F.Paste")
			(net "M_I_CPU1_SA_DQ<10>")
		)
		(pad "M21" smd circle
			(at -15.830042 -27.900122 180)
			(size 0.450088 0.450088)
			(layers "F.Cu" "F.Mask" "F.Paste")
			(net "M_I_CPU1_SA_DQ<9>")
		)
		(pad "M22" smd circle
			(at -14.889988 -27.900122 180)
			(size 0.450088 0.450088)
			(layers "F.Cu" "F.Mask" "F.Paste")
			(net "GND")
		)
		(pad "M23" smd circle
			(at -13.949934 -27.900122 180)
			(size 0.450088 0.450088)
			(layers "F.Cu" "F.Mask" "F.Paste")
			(net "PVDDCR_CPU0_P1")
		)
		(pad "M24" smd circle
			(at -13.00988 -27.900122 180)
			(size 0.450088 0.450088)
			(layers "F.Cu" "F.Mask" "F.Paste")
			(net "PVDDCR_CPU0_P1")
		)
		(pad "M25" smd circle
			(at -12.07008 -27.900122 180)
			(size 0.450088 0.450088)
			(layers "F.Cu" "F.Mask" "F.Paste")
			(net "GND")
		)
		(pad "M26" smd circle
			(at -11.130026 -27.900122 180)
			(size 0.450088 0.450088)
			(layers "F.Cu" "F.Mask" "F.Paste")
			(net "PVDDCR_CPU0_P1")
		)
		(pad "M27" smd circle
			(at -10.189972 -27.900122 180)
			(size 0.450088 0.450088)
			(layers "F.Cu" "F.Mask" "F.Paste")
			(net "PVDDCR_CPU0_P1")
		)
		(pad "M28" smd circle
			(at -9.249918 -27.900122 180)
			(size 0.450088 0.450088)
			(layers "F.Cu" "F.Mask" "F.Paste")
			(net "GND")
		)
		(pad "M29" smd circle
			(at -8.310118 -27.900122 180)
			(size 0.450088 0.450088)
			(layers "F.Cu" "F.Mask" "F.Paste")
			(net "PVDDCR_CPU0_P1")
		)
		(pad "M30" smd circle
			(at -7.370064 -27.900122 180)
			(size 0.450088 0.450088)
			(layers "F.Cu" "F.Mask" "F.Paste")
			(net "PVDDCR_CPU0_P1")
		)
		(pad "M31" smd circle
			(at -6.43001 -27.900122 180)
			(size 0.450088 0.450088)
			(layers "F.Cu" "F.Mask" "F.Paste")
			(net "GND")
		)
		(pad "M32" smd circle
			(at -5.489956 -27.900122 180)
			(size 0.450088 0.450088)
			(layers "F.Cu" "F.Mask" "F.Paste")
			(net "PVDDCR_CPU0_P1")
		)
		(pad "M33" smd circle
			(at -4.549902 -27.900122 180)
			(size 0.450088 0.450088)
			(layers "F.Cu" "F.Mask" "F.Paste")
			(net "PVDDCR_CPU0_P1")
		)
		(pad "M34" smd circle
			(at -3.610102 -27.900122 180)
			(size 0.450088 0.450088)
			(layers "F.Cu" "F.Mask" "F.Paste")
			(net "GND")
		)
		(pad "M35" smd circle
			(at -2.670048 -27.900122 180)
			(size 0.450088 0.450088)
			(layers "F.Cu" "F.Mask" "F.Paste")
			(net "GMI_CPU1_G2_CPU0_G0_TX_DP<0>")
		)
		(pad "M36" smd circle
			(at -1.729994 -27.900122 180)
			(size 0.450088 0.450088)
			(layers "F.Cu" "F.Mask" "F.Paste")
			(net "GMI_CPU1_G2_CPU0_G0_TX_DN<0>")
		)
		(pad "M37" smd circle
			(at -0.78994 -27.900122 180)
			(size 0.450088 0.450088)
			(layers "F.Cu" "F.Mask" "F.Paste")
			(net "GND")
		)
		(pad "M39" smd circle
			(at 1.089914 -27.900122 180)
			(size 0.450088 0.450088)
			(layers "F.Cu" "F.Mask" "F.Paste")
			(net "GND")
		)
		(pad "M40" smd circle
			(at 2.029968 -27.900122 180)
			(size 0.450088 0.450088)
			(layers "F.Cu" "F.Mask" "F.Paste")
			(net "GMI_CPU0_G2_CPU1_G0_TX_DN<15>")
		)
		(pad "M41" smd circle
			(at 2.970022 -27.900122 180)
			(size 0.450088 0.450088)
			(layers "F.Cu" "F.Mask" "F.Paste")
			(net "GMI_CPU0_G2_CPU1_G0_TX_DP<15>")
		)
		(pad "M42" smd circle
			(at 3.910076 -27.900122 180)
			(size 0.450088 0.450088)
			(layers "F.Cu" "F.Mask" "F.Paste")
			(net "GND")
		)
		(pad "M43" smd circle
			(at 4.849876 -27.900122 180)
			(size 0.450088 0.450088)
			(layers "F.Cu" "F.Mask" "F.Paste")
			(net "PVDDCR_CPU0_P1")
		)
		(pad "M44" smd circle
			(at 5.78993 -27.900122 180)
			(size 0.450088 0.450088)
			(layers "F.Cu" "F.Mask" "F.Paste")
			(net "PVDDCR_CPU0_P1")
		)
		(pad "M45" smd circle
			(at 6.729984 -27.900122 180)
			(size 0.450088 0.450088)
			(layers "F.Cu" "F.Mask" "F.Paste")
			(net "GND")
		)
		(pad "M46" smd circle
			(at 7.670038 -27.900122 180)
			(size 0.450088 0.450088)
			(layers "F.Cu" "F.Mask" "F.Paste")
			(net "PVDDCR_CPU0_P1")
		)
		(pad "M47" smd circle
			(at 8.610092 -27.900122 180)
			(size 0.450088 0.450088)
			(layers "F.Cu" "F.Mask" "F.Paste")
			(net "PVDDCR_CPU0_P1")
		)
		(pad "M48" smd circle
			(at 9.549892 -27.900122 180)
			(size 0.450088 0.450088)
			(layers "F.Cu" "F.Mask" "F.Paste")
			(net "GND")
		)
		(pad "M49" smd circle
			(at 10.489946 -27.900122 180)
			(size 0.450088 0.450088)
			(layers "F.Cu" "F.Mask" "F.Paste")
			(net "PVDDCR_CPU0_P1")
		)
		(pad "M50" smd circle
			(at 11.43 -27.900122 180)
			(size 0.450088 0.450088)
			(layers "F.Cu" "F.Mask" "F.Paste")
			(net "PVDDCR_CPU0_P1")
		)
		(pad "M51" smd circle
			(at 12.370054 -27.900122 180)
			(size 0.450088 0.450088)
			(layers "F.Cu" "F.Mask" "F.Paste")
			(net "GND")
		)
		(pad "M52" smd circle
			(at 13.310108 -27.900122 180)
			(size 0.450088 0.450088)
			(layers "F.Cu" "F.Mask" "F.Paste")
			(net "PVDDCR_CPU0_P1")
		)
		(pad "M53" smd circle
			(at 14.249908 -27.900122 180)
			(size 0.450088 0.450088)
			(layers "F.Cu" "F.Mask" "F.Paste")
			(net "PVDDCR_CPU0_P1")
		)
		(pad "M54" smd circle
			(at 15.189962 -27.900122 180)
			(size 0.450088 0.450088)
			(layers "F.Cu" "F.Mask" "F.Paste")
			(net "GND")
		)
		(pad "M55" smd circle
			(at 16.130016 -27.900122 180)
			(size 0.450088 0.450088)
			(layers "F.Cu" "F.Mask" "F.Paste")
			(net "M_C_CPU1_SA_DQ<9>")
		)
		(pad "M56" smd circle
			(at 17.07007 -27.900122 180)
			(size 0.450088 0.450088)
			(layers "F.Cu" "F.Mask" "F.Paste")
			(net "M_C_CPU1_SA_DQ<10>")
		)
		(pad "M57" smd circle
			(at 18.010124 -27.900122 180)
			(size 0.450088 0.450088)
			(layers "F.Cu" "F.Mask" "F.Paste")
			(net "GND")
		)
		(pad "M58" smd circle
			(at 18.949924 -27.900122 180)
			(size 0.450088 0.450088)
			(layers "F.Cu" "F.Mask" "F.Paste")
			(net "M_D_CPU1_SA_DQ<9>")
		)
		(pad "M59" smd circle
			(at 19.889978 -27.900122 180)
			(size 0.450088 0.450088)
			(layers "F.Cu" "F.Mask" "F.Paste")
			(net "GND")
		)
		(pad "M60" smd circle
			(at 20.830032 -27.900122 180)
			(size 0.450088 0.450088)
			(layers "F.Cu" "F.Mask" "F.Paste")
			(net "M_D_CPU1_SA_DQ<10>")
		)
		(pad "M61" smd circle
			(at 21.770086 -27.900122 180)
			(size 0.450088 0.450088)
			(layers "F.Cu" "F.Mask" "F.Paste")
			(net "GND")
		)
		(pad "M62" smd circle
			(at 22.709886 -27.900122 180)
			(size 0.450088 0.450088)
			(layers "F.Cu" "F.Mask" "F.Paste")
			(net "M_B_CPU1_SA_DQ<9>")
		)
		(pad "M63" smd circle
			(at 23.64994 -27.900122 180)
			(size 0.450088 0.450088)
			(layers "F.Cu" "F.Mask" "F.Paste")
			(net "M_B_CPU1_SA_DQ<10>")
		)
		(pad "M64" smd circle
			(at 24.589994 -27.900122 180)
			(size 0.450088 0.450088)
			(layers "F.Cu" "F.Mask" "F.Paste")
			(net "GND")
		)
		(pad "M65" smd circle
			(at 25.530048 -27.900122 180)
			(size 0.450088 0.450088)
			(layers "F.Cu" "F.Mask" "F.Paste")
			(net "M_F_CPU1_SA_DQ<9>")
		)
		(pad "M66" smd circle
			(at 26.470102 -27.900122 180)
			(size 0.450088 0.450088)
			(layers "F.Cu" "F.Mask" "F.Paste")
			(net "GND")
		)
		(pad "M67" smd circle
			(at 27.409902 -27.900122 180)
			(size 0.450088 0.450088)
			(layers "F.Cu" "F.Mask" "F.Paste")
			(net "M_F_CPU1_SA_DQ<10>")
		)
		(pad "M68" smd circle
			(at 28.349956 -27.900122 180)
			(size 0.450088 0.450088)
			(layers "F.Cu" "F.Mask" "F.Paste")
			(net "GND")
		)
		(pad "M69" smd circle
			(at 29.29001 -27.900122 180)
			(size 0.450088 0.450088)
			(layers "F.Cu" "F.Mask" "F.Paste")
			(net "M_E_CPU1_SA_DQ<9>")
		)
		(pad "M70" smd circle
			(at 30.230064 -27.900122 180)
			(size 0.450088 0.450088)
			(layers "F.Cu" "F.Mask" "F.Paste")
			(net "M_E_CPU1_SA_DQ<10>")
		)
		(pad "M71" smd circle
			(at 31.170118 -27.900122 180)
			(size 0.450088 0.450088)
			(layers "F.Cu" "F.Mask" "F.Paste")
			(net "GND")
		)
		(pad "M72" smd circle
			(at 32.109918 -27.900122 180)
			(size 0.450088 0.450088)
			(layers "F.Cu" "F.Mask" "F.Paste")
			(net "M_A_CPU1_SA_DQ<9>")
		)
		(pad "M73" smd circle
			(at 33.049972 -27.900122 180)
			(size 0.450088 0.450088)
			(layers "F.Cu" "F.Mask" "F.Paste")
			(net "GND")
		)
		(pad "M74" smd circle
			(at 33.990026 -27.900122 180)
			(size 0.450088 0.450088)
			(layers "F.Cu" "F.Mask" "F.Paste")
			(net "M_A_CPU1_SA_DQ<10>")
		)
		(pad "N1" smd circle
			(at -34.159952 -27.090116 180)
			(size 0.450088 0.450088)
			(layers "F.Cu" "F.Mask" "F.Paste")
			(net "GND")
		)
		(pad "N2" smd circle
			(at -33.219898 -27.090116 180)
			(size 0.450088 0.450088)
			(layers "F.Cu" "F.Mask" "F.Paste")
			(net "M_G_CPU1_SA_DQS_DP<1>")
		)
		(pad "N3" smd circle
			(at -32.280098 -27.090116 180)
			(size 0.450088 0.450088)
			(layers "F.Cu" "F.Mask" "F.Paste")
			(net "M_G_CPU1_SA_DQ<11>")
		)
		(pad "N4" smd circle
			(at -31.340044 -27.090116 180)
			(size 0.450088 0.450088)
			(layers "F.Cu" "F.Mask" "F.Paste")
			(net "GND")
		)
		(pad "N5" smd circle
			(at -30.39999 -27.090116 180)
			(size 0.450088 0.450088)
			(layers "F.Cu" "F.Mask" "F.Paste")
			(net "M_K_CPU1_SA_DQS_DP<1>")
		)
		(pad "N6" smd circle
			(at -29.459936 -27.090116 180)
			(size 0.450088 0.450088)
			(layers "F.Cu" "F.Mask" "F.Paste")
			(net "GND")
		)
		(pad "N7" smd circle
			(at -28.519882 -27.090116 180)
			(size 0.450088 0.450088)
			(layers "F.Cu" "F.Mask" "F.Paste")
			(net "M_K_CPU1_SA_DQ<11>")
		)
		(pad "N8" smd circle
			(at -27.580082 -27.090116 180)
			(size 0.450088 0.450088)
			(layers "F.Cu" "F.Mask" "F.Paste")
			(net "GND")
		)
		(pad "N9" smd circle
			(at -26.640028 -27.090116 180)
			(size 0.450088 0.450088)
			(layers "F.Cu" "F.Mask" "F.Paste")
			(net "M_L_CPU1_SA_DQS_DP<1>")
		)
		(pad "N10" smd circle
			(at -25.699974 -27.090116 180)
			(size 0.450088 0.450088)
			(layers "F.Cu" "F.Mask" "F.Paste")
			(net "M_L_CPU1_SA_DQ<11>")
		)
		(pad "N11" smd circle
			(at -24.75992 -27.090116 180)
			(size 0.450088 0.450088)
			(layers "F.Cu" "F.Mask" "F.Paste")
			(net "GND")
		)
		(pad "N12" smd circle
			(at -23.82012 -27.090116 180)
			(size 0.450088 0.450088)
			(layers "F.Cu" "F.Mask" "F.Paste")
			(net "M_H_CPU1_SA_DQS_DP<1>")
		)
		(pad "N13" smd circle
			(at -22.880066 -27.090116 180)
			(size 0.450088 0.450088)
			(layers "F.Cu" "F.Mask" "F.Paste")
			(net "GND")
		)
		(pad "N14" smd circle
			(at -21.940012 -27.090116 180)
			(size 0.450088 0.450088)
			(layers "F.Cu" "F.Mask" "F.Paste")
			(net "M_H_CPU1_SA_DQ<11>")
		)
		(pad "N15" smd circle
			(at -20.999958 -27.090116 180)
			(size 0.450088 0.450088)
			(layers "F.Cu" "F.Mask" "F.Paste")
			(net "GND")
		)
		(pad "N16" smd circle
			(at -20.059904 -27.090116 180)
			(size 0.450088 0.450088)
			(layers "F.Cu" "F.Mask" "F.Paste")
			(net "M_J_CPU1_SA_DQS_DP<1>")
		)
		(pad "N17" smd circle
			(at -19.120104 -27.090116 180)
			(size 0.450088 0.450088)
			(layers "F.Cu" "F.Mask" "F.Paste")
			(net "M_J_CPU1_SA_DQ<11>")
		)
		(pad "N18" smd circle
			(at -18.18005 -27.090116 180)
			(size 0.450088 0.450088)
			(layers "F.Cu" "F.Mask" "F.Paste")
			(net "GND")
		)
		(pad "N19" smd circle
			(at -17.239996 -27.090116 180)
			(size 0.450088 0.450088)
			(layers "F.Cu" "F.Mask" "F.Paste")
			(net "M_I_CPU1_SA_DQS_DP<1>")
		)
		(pad "N20" smd circle
			(at -16.299942 -27.090116 180)
			(size 0.450088 0.450088)
			(layers "F.Cu" "F.Mask" "F.Paste")
			(net "GND")
		)
		(pad "N21" smd circle
			(at -15.359888 -27.090116 180)
			(size 0.450088 0.450088)
			(layers "F.Cu" "F.Mask" "F.Paste")
			(net "M_I_CPU1_SA_DQ<11>")
		)
		(pad "N22" smd circle
			(at -14.420088 -27.090116 180)
			(size 0.450088 0.450088)
			(layers "F.Cu" "F.Mask" "F.Paste")
			(net "GND")
		)
		(pad "N23" smd circle
			(at -13.480034 -27.090116 180)
			(size 0.450088 0.450088)
			(layers "F.Cu" "F.Mask" "F.Paste")
			(net "GMI_CPU1_G2_CPU0_G0_TX_DP<15>")
		)
		(pad "N24" smd circle
			(at -12.53998 -27.090116 180)
			(size 0.450088 0.450088)
			(layers "F.Cu" "F.Mask" "F.Paste")
			(net "GMI_CPU1_G2_CPU0_G0_TX_DN<15>")
		)
		(pad "N25" smd circle
			(at -11.599926 -27.090116 180)
			(size 0.450088 0.450088)
			(layers "F.Cu" "F.Mask" "F.Paste")
			(net "GND")
		)
		(pad "N26" smd circle
			(at -10.659872 -27.090116 180)
			(size 0.450088 0.450088)
			(layers "F.Cu" "F.Mask" "F.Paste")
			(net "GMI_CPU1_G3_CPU0_G1_TX_DP<10>")
		)
		(pad "N27" smd circle
			(at -9.720072 -27.090116 180)
			(size 0.450088 0.450088)
			(layers "F.Cu" "F.Mask" "F.Paste")
			(net "GMI_CPU1_G3_CPU0_G1_TX_DN<10>")
		)
		(pad "N28" smd circle
			(at -8.780018 -27.090116 180)
			(size 0.450088 0.450088)
			(layers "F.Cu" "F.Mask" "F.Paste")
			(net "GND")
		)
		(pad "N29" smd circle
			(at -7.839964 -27.090116 180)
			(size 0.450088 0.450088)
			(layers "F.Cu" "F.Mask" "F.Paste")
			(net "GMI_CPU1_G3_CPU0_G1_TX_DP<7>")
		)
		(pad "N30" smd circle
			(at -6.89991 -27.090116 180)
			(size 0.450088 0.450088)
			(layers "F.Cu" "F.Mask" "F.Paste")
			(net "GMI_CPU1_G3_CPU0_G1_TX_DN<7>")
		)
		(pad "N31" smd circle
			(at -5.96011 -27.090116 180)
			(size 0.450088 0.450088)
			(layers "F.Cu" "F.Mask" "F.Paste")
			(net "GND")
		)
		(pad "N32" smd circle
			(at -5.020056 -27.090116 180)
			(size 0.450088 0.450088)
			(layers "F.Cu" "F.Mask" "F.Paste")
			(net "GMI_CPU1_G3_CPU0_G1_TX_DP<4>")
		)
		(pad "N33" smd circle
			(at -4.080002 -27.090116 180)
			(size 0.450088 0.450088)
			(layers "F.Cu" "F.Mask" "F.Paste")
			(net "GMI_CPU1_G3_CPU0_G1_TX_DN<4>")
		)
	)
)
